(kicad_pcb
	(version 20260206)
	(generator "pcbnew")
	(generator_version "10.0")
	(general
		(thickness 1.6)
		(legacy_teardrops no)
	)
	(paper "A4")
	(title_block
		(title "03242023_DA0F0TMBIJ0_F0T_Motherboard_J_brd_V01_OCP.brd")
		(comment 1 "Grand Teton / footprint 3039 of 6105 (U2), pads 4436-4541 of 4677")
	)
	(layers
		(0 "F.Cu" signal "TOP")
		(4 "In1.Cu" signal "GND")
		(6 "In2.Cu" signal "IN1")
		(8 "In3.Cu" signal "GND1")
		(10 "In4.Cu" signal "IN2")
		(12 "In5.Cu" signal "GND2")
		(14 "In6.Cu" signal "IN3")
		(16 "In7.Cu" signal "GND3")
		(18 "In8.Cu" signal "VCC")
		(20 "In9.Cu" signal "VCC1")
		(22 "In10.Cu" signal "GND4")
		(24 "In11.Cu" signal "IN4")
		(26 "In12.Cu" signal "GND5")
		(28 "In13.Cu" signal "IN5")
		(30 "In14.Cu" signal "GND6")
		(32 "In15.Cu" signal "IN6")
		(34 "In16.Cu" signal "GND7")
		(2 "B.Cu" signal "BOTTOM")
		(9 "F.Adhes" user "F.Adhesive")
		(11 "B.Adhes" user "B.Adhesive")
		(13 "F.Paste" user "Package Geometry/Pastemask Top")
		(15 "B.Paste" user "Package Geometry/Pastemask Bottom")
		(5 "F.SilkS" user "Ref Des/Silkscreen Top")
		(7 "B.SilkS" user "Ref Des/Silkscreen Bottom")
		(1 "F.Mask" user "Board Geometry/Soldermask Top")
		(3 "B.Mask" user "Board Geometry/Soldermask Bottom")
		(17 "Dwgs.User" user "User.Drawings")
		(19 "Cmts.User" user "User.Comments")
		(21 "Eco1.User" user "User.Eco1")
		(23 "Eco2.User" user "User.Eco2")
		(25 "Edge.Cuts" user "Board Geometry/Outline")
		(27 "Margin" user)
		(31 "F.CrtYd" user "Package Geometry/Place Bound Top")
		(29 "B.CrtYd" user "Package Geometry/Place Bound Bottom")
		(35 "F.Fab" user "Ref Des/Assembly Top")
		(33 "B.Fab" user "Ref Des/Assembly Bottom")
	)
	(footprint ""
		(layer "F.Cu")
		(at 359.870248 -251.76988 90)
		(property "Reference" "U2"
			(at -74.416158 -44.488608 0)
			(unlocked yes)
			(layer "F.SilkS")
			(effects
				(font
					(size 1.6002 1.1938)
					(thickness 0.1524)
				)
				(justify left)
			)
		)
		(property "Value" ""
			(at 0 0 90)
			(layer "F.Fab")
			(effects
				(font
					(size 1.27 1.27)
				)
			)
		)
		(duplicate_pad_numbers_are_jumpers no)
		(pad "R58" smd circle
			(at 10.566654 -20.385532 270)
			(size 0.4318 0.4318)
			(layers "F.Cu" "F.Mask" "F.Paste")
			(net "M_B_CPU0_SA_DQS_DN<3>")
		)
		(pad "R60" smd circle
			(at 12.19454 -20.385532 270)
			(size 0.4318 0.4318)
			(layers "F.Cu" "F.Mask" "F.Paste")
			(net "GND")
		)
		(pad "R62" smd circle
			(at 13.822426 -20.385532 270)
			(size 0.4318 0.4318)
			(layers "F.Cu" "F.Mask" "F.Paste")
			(net "GND")
		)
		(pad "R64" smd circle
			(at 15.450058 -20.385532 270)
			(size 0.4318 0.4318)
			(layers "F.Cu" "F.Mask" "F.Paste")
			(net "M_C_CPU0_SA_DQS_DN<2>")
		)
		(pad "R66" smd circle
			(at 17.07769 -20.385532 270)
			(size 0.4318 0.4318)
			(layers "F.Cu" "F.Mask" "F.Paste")
			(net "GND")
		)
		(pad "R68" smd circle
			(at 18.705576 -20.385532 270)
			(size 0.4318 0.4318)
			(layers "F.Cu" "F.Mask" "F.Paste")
			(net "GND")
		)
		(pad "R70" smd circle
			(at 20.333462 -20.385532 270)
			(size 0.4318 0.4318)
			(layers "F.Cu" "F.Mask" "F.Paste")
			(net "M_B_CPU0_SA_DQS_DN<1>")
		)
		(pad "R72" smd circle
			(at 21.961094 -20.385532 270)
			(size 0.4318 0.4318)
			(layers "F.Cu" "F.Mask" "F.Paste")
			(net "GND")
		)
		(pad "R74" smd circle
			(at 23.58898 -20.385532 270)
			(size 0.4318 0.4318)
			(layers "F.Cu" "F.Mask" "F.Paste")
			(net "GND")
		)
		(pad "R76" smd circle
			(at 25.216612 -20.385532 270)
			(size 0.4318 0.4318)
			(layers "F.Cu" "F.Mask" "F.Paste")
			(net "M_C_CPU0_SA_DQS_DN<0>")
		)
		(pad "R78" smd circle
			(at 26.844498 -20.385532 270)
			(size 0.4318 0.4318)
			(layers "F.Cu" "F.Mask" "F.Paste")
			(net "GND")
		)
		(pad "R80" smd circle
			(at 28.472384 -20.385532 270)
			(size 0.4318 0.4318)
			(layers "F.Cu" "F.Mask" "F.Paste")
			(net "PVCCFA_EHV_FIVRA_CPU0")
		)
		(pad "R82" smd circle
			(at 30.100016 -20.385532 270)
			(size 0.4318 0.4318)
			(layers "F.Cu" "F.Mask" "F.Paste")
			(net "UPI_CPU0_CPU1_P2P2_DN<17>")
		)
		(pad "R84" smd circle
			(at 31.727902 -20.385532 270)
			(size 0.4318 0.4318)
			(layers "F.Cu" "F.Mask" "F.Paste")
			(net "GND")
		)
		(pad "R86" smd circle
			(at 33.355534 -20.385532 270)
			(size 0.4318 0.4318)
			(layers "F.Cu" "F.Mask" "F.Paste")
			(net "P5E_CPU0_PE4_TX_DN<2>")
		)
		(pad "R88" smd circle
			(at 34.98342 -20.385532 270)
			(size 0.4318 0.4318)
			(layers "F.Cu" "F.Mask" "F.Paste")
			(net "GND")
		)
		(pad "R90" smd circle
			(at 36.611306 -20.385532 270)
			(size 0.4318 0.4318)
			(layers "F.Cu" "F.Mask" "F.Paste")
			(net "P5E_CPU0_PE4_RX_DP<2>")
		)
		(pad "T2" smd circle
			(at -36.611306 -20.025868 270)
			(size 0.4318 0.4318)
			(layers "F.Cu" "F.Mask" "F.Paste")
			(net "UPI_CPU0_CPU1_P0P1_DN<3>")
		)
		(pad "T4" smd circle
			(at -34.98342 -20.025868 270)
			(size 0.4318 0.4318)
			(layers "F.Cu" "F.Mask" "F.Paste")
			(net "GND")
		)
		(pad "T6" smd circle
			(at -33.355534 -20.025868 270)
			(size 0.4318 0.4318)
			(layers "F.Cu" "F.Mask" "F.Paste")
			(net "UPI_CPU1_CPU0_P1P0_DN<3>")
		)
		(pad "T8" smd circle
			(at -31.727902 -20.025868 270)
			(size 0.4318 0.4318)
			(layers "F.Cu" "F.Mask" "F.Paste")
			(net "GND")
		)
		(pad "T10" smd circle
			(at -30.100016 -20.025868 270)
			(size 0.4318 0.4318)
			(layers "F.Cu" "F.Mask" "F.Paste")
			(net "P5E_CPU0_PE0_RX_DN<3>")
		)
		(pad "T12" smd circle
			(at -28.472384 -20.025868 270)
			(size 0.4318 0.4318)
			(layers "F.Cu" "F.Mask" "F.Paste")
			(net "GND")
		)
		(pad "T14" smd circle
			(at -26.844498 -20.025868 270)
			(size 0.4318 0.4318)
			(layers "F.Cu" "F.Mask" "F.Paste")
			(net "P5E_CPU0_PE0_TX_DP<2>")
		)
		(pad "T16" smd circle
			(at -25.216612 -20.025868 270)
			(size 0.4318 0.4318)
			(layers "F.Cu" "F.Mask" "F.Paste")
			(net "GND")
		)
		(pad "T18" smd circle
			(at -23.58898 -20.025868 270)
			(size 0.4318 0.4318)
			(layers "F.Cu" "F.Mask" "F.Paste")
			(net "GND")
		)
		(pad "T20" smd circle
			(at -21.961094 -20.025868 270)
			(size 0.4318 0.4318)
			(layers "F.Cu" "F.Mask" "F.Paste")
			(net "M_C_CPU0_SB_DQ<20>")
		)
		(pad "T22" smd circle
			(at -20.333462 -20.025868 270)
			(size 0.4318 0.4318)
			(layers "F.Cu" "F.Mask" "F.Paste")
			(net "M_C_CPU0_SB_DQ<17>")
		)
		(pad "T24" smd circle
			(at -18.705576 -20.025868 270)
			(size 0.4318 0.4318)
			(layers "F.Cu" "F.Mask" "F.Paste")
			(net "GND")
		)
		(pad "T26" smd circle
			(at -17.07769 -20.025868 270)
			(size 0.4318 0.4318)
			(layers "F.Cu" "F.Mask" "F.Paste")
			(net "M_B_CPU0_SB_DQ<4>")
		)
		(pad "T28" smd circle
			(at -15.450058 -20.025868 270)
			(size 0.4318 0.4318)
			(layers "F.Cu" "F.Mask" "F.Paste")
			(net "M_B_CPU0_SB_DQ<1>")
		)
		(pad "T30" smd circle
			(at -13.822426 -20.025868 270)
			(size 0.4318 0.4318)
			(layers "F.Cu" "F.Mask" "F.Paste")
			(net "GND")
		)
		(pad "T32" smd circle
			(at -12.19454 -20.025868 270)
			(size 0.4318 0.4318)
			(layers "F.Cu" "F.Mask" "F.Paste")
			(net "M_C_CPU0_SB_CB<0>")
		)
		(pad "T34" smd circle
			(at -10.566654 -20.025868 270)
			(size 0.4318 0.4318)
			(layers "F.Cu" "F.Mask" "F.Paste")
			(net "M_C_CPU0_SB_CB<5>")
		)
		(pad "T36" smd circle
			(at -8.939022 -20.025868 270)
			(size 0.4318 0.4318)
			(layers "F.Cu" "F.Mask" "F.Paste")
			(net "GND")
		)
		(pad "T38" smd circle
			(at -7.311136 -20.025868 270)
			(size 0.4318 0.4318)
			(layers "F.Cu" "F.Mask" "F.Paste")
			(net "M_C_CPU0_SB_CS_N<0>")
		)
		(pad "T40" smd circle
			(at -5.68325 -20.025868 270)
			(size 0.4318 0.4318)
			(layers "F.Cu" "F.Mask" "F.Paste")
			(net "M_C_CPU0_SB_CA<4>")
		)
		(pad "T42" smd circle
			(at -4.055618 -20.025868 270)
			(size 0.4318 0.4318)
			(layers "F.Cu" "F.Mask" "F.Paste")
			(net "GND")
		)
		(pad "T44" smd circle
			(at -2.427732 -20.025868 270)
			(size 0.4318 0.4318)
			(layers "F.Cu" "F.Mask" "F.Paste")
			(net "M_B_CPU0_SB_CA<0>")
		)
		(pad "T47" smd circle
			(at 1.613916 -19.915886 270)
			(size 0.4318 0.4318)
			(layers "F.Cu" "F.Mask" "F.Paste")
			(net "M_C_CPU0_SA_PAR")
		)
		(pad "T49" smd circle
			(at 3.241802 -19.915886 270)
			(size 0.4318 0.4318)
			(layers "F.Cu" "F.Mask" "F.Paste")
			(net "GND")
		)
		(pad "T51" smd circle
			(at 4.869434 -19.915886 270)
			(size 0.4318 0.4318)
			(layers "F.Cu" "F.Mask" "F.Paste")
			(net "M_C_CPU0_SA_CA<2>")
		)
		(pad "T53" smd circle
			(at 6.49732 -19.915886 270)
			(size 0.4318 0.4318)
			(layers "F.Cu" "F.Mask" "F.Paste")
			(net "M_C_CPU0_SA_CS_N<1>")
		)
		(pad "T55" smd circle
			(at 8.124952 -19.915886 270)
			(size 0.4318 0.4318)
			(layers "F.Cu" "F.Mask" "F.Paste")
			(net "GND")
		)
		(pad "T57" smd circle
			(at 9.752838 -19.915886 270)
			(size 0.4318 0.4318)
			(layers "F.Cu" "F.Mask" "F.Paste")
			(net "M_B_CPU0_SA_DQ<28>")
		)
		(pad "T59" smd circle
			(at 11.380724 -19.915886 270)
			(size 0.4318 0.4318)
			(layers "F.Cu" "F.Mask" "F.Paste")
			(net "M_B_CPU0_SA_DQ<25>")
		)
		(pad "T61" smd circle
			(at 13.008356 -19.915886 270)
			(size 0.4318 0.4318)
			(layers "F.Cu" "F.Mask" "F.Paste")
			(net "GND")
		)
		(pad "T63" smd circle
			(at 14.635988 -19.915886 270)
			(size 0.4318 0.4318)
			(layers "F.Cu" "F.Mask" "F.Paste")
			(net "M_C_CPU0_SA_DQ<20>")
		)
		(pad "T65" smd circle
			(at 16.263874 -19.915886 270)
			(size 0.4318 0.4318)
			(layers "F.Cu" "F.Mask" "F.Paste")
			(net "M_C_CPU0_SA_DQ<17>")
		)
		(pad "T67" smd circle
			(at 17.89176 -19.915886 270)
			(size 0.4318 0.4318)
			(layers "F.Cu" "F.Mask" "F.Paste")
			(net "GND")
		)
		(pad "T69" smd circle
			(at 19.519392 -19.915886 270)
			(size 0.4318 0.4318)
			(layers "F.Cu" "F.Mask" "F.Paste")
			(net "M_B_CPU0_SA_DQ<12>")
		)
		(pad "T71" smd circle
			(at 21.147278 -19.915886 270)
			(size 0.4318 0.4318)
			(layers "F.Cu" "F.Mask" "F.Paste")
			(net "M_B_CPU0_SA_DQ<9>")
		)
		(pad "T73" smd circle
			(at 22.77491 -19.915886 270)
			(size 0.4318 0.4318)
			(layers "F.Cu" "F.Mask" "F.Paste")
			(net "GND")
		)
		(pad "T75" smd circle
			(at 24.402796 -19.915886 270)
			(size 0.4318 0.4318)
			(layers "F.Cu" "F.Mask" "F.Paste")
			(net "M_C_CPU0_SA_DQ<4>")
		)
		(pad "T77" smd circle
			(at 26.030682 -19.915886 270)
			(size 0.4318 0.4318)
			(layers "F.Cu" "F.Mask" "F.Paste")
			(net "M_C_CPU0_SA_DQ<1>")
		)
		(pad "T79" smd circle
			(at 27.658314 -19.915886 270)
			(size 0.4318 0.4318)
			(layers "F.Cu" "F.Mask" "F.Paste")
			(net "GND")
		)
		(pad "T81" smd circle
			(at 29.2862 -19.915886 270)
			(size 0.4318 0.4318)
			(layers "F.Cu" "F.Mask" "F.Paste")
			(net "UPI_CPU0_CPU1_P2P2_DP<18>")
		)
		(pad "T83" smd circle
			(at 30.914086 -19.915886 270)
			(size 0.4318 0.4318)
			(layers "F.Cu" "F.Mask" "F.Paste")
			(net "GND")
		)
		(pad "T85" smd circle
			(at 32.541718 -19.915886 270)
			(size 0.4318 0.4318)
			(layers "F.Cu" "F.Mask" "F.Paste")
			(net "PVCCFA_EHV_FIVRA_CPU0")
		)
		(pad "T87" smd circle
			(at 34.169604 -19.915886 270)
			(size 0.4318 0.4318)
			(layers "F.Cu" "F.Mask" "F.Paste")
			(net "P5E_CPU0_PE4_TX_DP<2>")
		)
		(pad "T89" smd circle
			(at 35.797236 -19.915886 270)
			(size 0.4318 0.4318)
			(layers "F.Cu" "F.Mask" "F.Paste")
			(net "PVCCFA_EHV_FIVRA_CPU0")
		)
		(pad "T91" smd oval
			(at 37.425122 -19.915886)
			(size 0.381 0.4826)
			(drill
				(offset 0 -0.0508)
			)
			(layers "F.Cu" "F.Mask" "F.Paste")
			(net "P5E_CPU0_PE4_RX_DN<2>")
		)
		(pad "U1" smd oval
			(at -37.425122 -19.555714 180)
			(size 0.381 0.4826)
			(drill
				(offset 0 -0.0508)
			)
			(layers "F.Cu" "F.Mask" "F.Paste")
			(net "UPI_CPU0_CPU1_P0P1_DN<4>")
		)
		(pad "U3" smd circle
			(at -35.797236 -19.555714 270)
			(size 0.4318 0.4318)
			(layers "F.Cu" "F.Mask" "F.Paste")
			(net "PVCCFA_EHV_CPU0")
		)
		(pad "U5" smd circle
			(at -34.169604 -19.555714 270)
			(size 0.4318 0.4318)
			(layers "F.Cu" "F.Mask" "F.Paste")
			(net "UPI_CPU1_CPU0_P1P0_DP<3>")
		)
		(pad "U7" smd circle
			(at -32.541718 -19.555714 270)
			(size 0.4318 0.4318)
			(layers "F.Cu" "F.Mask" "F.Paste")
			(net "PVCCFA_EHV_FIVRA_CPU0")
		)
		(pad "U9" smd circle
			(at -30.914086 -19.555714 270)
			(size 0.4318 0.4318)
			(layers "F.Cu" "F.Mask" "F.Paste")
			(net "P5E_CPU0_PE0_RX_DP<3>")
		)
		(pad "U11" smd circle
			(at -29.2862 -19.555714 270)
			(size 0.4318 0.4318)
			(layers "F.Cu" "F.Mask" "F.Paste")
			(net "PVCCFA_EHV_FIVRA_CPU0")
		)
		(pad "U13" smd circle
			(at -27.658314 -19.555714 270)
			(size 0.4318 0.4318)
			(layers "F.Cu" "F.Mask" "F.Paste")
			(net "P5E_CPU0_PE0_TX_DN<2>")
		)
		(pad "U15" smd circle
			(at -26.030682 -19.555714 270)
			(size 0.4318 0.4318)
			(layers "F.Cu" "F.Mask" "F.Paste")
			(net "PVCCFA_EHV_FIVRA_CPU0")
		)
		(pad "U17" smd circle
			(at -24.402796 -19.555714 270)
			(size 0.4318 0.4318)
			(layers "F.Cu" "F.Mask" "F.Paste")
			(net "NC_CPU0_HBM0_VIEWDIG0")
		)
		(pad "U19" smd circle
			(at -22.77491 -19.555714 270)
			(size 0.4318 0.4318)
			(layers "F.Cu" "F.Mask" "F.Paste")
			(net "M_C_CPU0_SB_DQ<21>")
		)
		(pad "U21" smd circle
			(at -21.147278 -19.555714 270)
			(size 0.4318 0.4318)
			(layers "F.Cu" "F.Mask" "F.Paste")
			(net "M_C_CPU0_SB_DQS_DP<2>")
		)
		(pad "U23" smd circle
			(at -19.519392 -19.555714 270)
			(size 0.4318 0.4318)
			(layers "F.Cu" "F.Mask" "F.Paste")
			(net "M_C_CPU0_SB_DQ<16>")
		)
		(pad "U25" smd circle
			(at -17.89176 -19.555714 270)
			(size 0.4318 0.4318)
			(layers "F.Cu" "F.Mask" "F.Paste")
			(net "M_B_CPU0_SB_DQ<5>")
		)
		(pad "U27" smd circle
			(at -16.263874 -19.555714 270)
			(size 0.4318 0.4318)
			(layers "F.Cu" "F.Mask" "F.Paste")
			(net "M_B_CPU0_SB_DQS_DP<0>")
		)
		(pad "U29" smd circle
			(at -14.635988 -19.555714 270)
			(size 0.4318 0.4318)
			(layers "F.Cu" "F.Mask" "F.Paste")
			(net "M_B_CPU0_SB_DQ<0>")
		)
		(pad "U31" smd circle
			(at -13.008356 -19.555714 270)
			(size 0.4318 0.4318)
			(layers "F.Cu" "F.Mask" "F.Paste")
			(net "M_C_CPU0_SB_CB<1>")
		)
		(pad "U33" smd circle
			(at -11.380724 -19.555714 270)
			(size 0.4318 0.4318)
			(layers "F.Cu" "F.Mask" "F.Paste")
			(net "M_C_CPU0_SB_DQS_DP<9>")
		)
		(pad "U35" smd circle
			(at -9.752838 -19.555714 270)
			(size 0.4318 0.4318)
			(layers "F.Cu" "F.Mask" "F.Paste")
			(net "M_C_CPU0_SB_CB<4>")
		)
		(pad "U37" smd circle
			(at -8.124952 -19.555714 270)
			(size 0.4318 0.4318)
			(layers "F.Cu" "F.Mask" "F.Paste")
			(net "M_C_CPU0_SB_CS_N<1>")
		)
		(pad "U39" smd circle
			(at -6.49732 -19.555714 270)
			(size 0.4318 0.4318)
			(layers "F.Cu" "F.Mask" "F.Paste")
			(net "GND")
		)
		(pad "U41" smd circle
			(at -4.869434 -19.555714 270)
			(size 0.4318 0.4318)
			(layers "F.Cu" "F.Mask" "F.Paste")
			(net "M_C_CPU0_SB_CA<2>")
		)
		(pad "U43" smd circle
			(at -3.241802 -19.555714 270)
			(size 0.4318 0.4318)
			(layers "F.Cu" "F.Mask" "F.Paste")
			(net "M_B_CPU0_SB_CA<1>")
		)
		(pad "U45" smd circle
			(at -1.613916 -19.555714 270)
			(size 0.4318 0.4318)
			(layers "F.Cu" "F.Mask" "F.Paste")
			(net "M_B_CPU0_CLK_DP<0>")
		)
		(pad "U48" smd circle
			(at 2.427732 -19.445732 270)
			(size 0.4318 0.4318)
			(layers "F.Cu" "F.Mask" "F.Paste")
			(net "M_C_CPU0_SA_CA<6>")
		)
		(pad "U50" smd circle
			(at 4.055618 -19.445732 270)
			(size 0.4318 0.4318)
			(layers "F.Cu" "F.Mask" "F.Paste")
			(net "M_C_CPU0_SA_CA<4>")
		)
		(pad "U52" smd circle
			(at 5.68325 -19.445732 270)
			(size 0.4318 0.4318)
			(layers "F.Cu" "F.Mask" "F.Paste")
			(net "GND")
		)
		(pad "U54" smd circle
			(at 7.311136 -19.445732 270)
			(size 0.4318 0.4318)
			(layers "F.Cu" "F.Mask" "F.Paste")
			(net "M_C_CPU0_SA_CS_N<0>")
		)
		(pad "U56" smd circle
			(at 8.939022 -19.445732 270)
			(size 0.4318 0.4318)
			(layers "F.Cu" "F.Mask" "F.Paste")
			(net "M_B_CPU0_SA_DQ<29>")
		)
		(pad "U58" smd circle
			(at 10.566654 -19.445732 270)
			(size 0.4318 0.4318)
			(layers "F.Cu" "F.Mask" "F.Paste")
			(net "M_B_CPU0_SA_DQS_DP<3>")
		)
		(pad "U60" smd circle
			(at 12.19454 -19.445732 270)
			(size 0.4318 0.4318)
			(layers "F.Cu" "F.Mask" "F.Paste")
			(net "M_B_CPU0_SA_DQ<24>")
		)
		(pad "U62" smd circle
			(at 13.822426 -19.445732 270)
			(size 0.4318 0.4318)
			(layers "F.Cu" "F.Mask" "F.Paste")
			(net "M_C_CPU0_SA_DQ<21>")
		)
		(pad "U64" smd circle
			(at 15.450058 -19.445732 270)
			(size 0.4318 0.4318)
			(layers "F.Cu" "F.Mask" "F.Paste")
			(net "M_C_CPU0_SA_DQS_DP<2>")
		)
		(pad "U66" smd circle
			(at 17.07769 -19.445732 270)
			(size 0.4318 0.4318)
			(layers "F.Cu" "F.Mask" "F.Paste")
			(net "M_C_CPU0_SA_DQ<16>")
		)
		(pad "U68" smd circle
			(at 18.705576 -19.445732 270)
			(size 0.4318 0.4318)
			(layers "F.Cu" "F.Mask" "F.Paste")
			(net "M_B_CPU0_SA_DQ<13>")
		)
		(pad "U70" smd circle
			(at 20.333462 -19.445732 270)
			(size 0.4318 0.4318)
			(layers "F.Cu" "F.Mask" "F.Paste")
			(net "M_B_CPU0_SA_DQS_DP<1>")
		)
		(pad "U72" smd circle
			(at 21.961094 -19.445732 270)
			(size 0.4318 0.4318)
			(layers "F.Cu" "F.Mask" "F.Paste")
			(net "M_B_CPU0_SA_DQ<8>")
		)
		(pad "U74" smd circle
			(at 23.58898 -19.445732 270)
			(size 0.4318 0.4318)
			(layers "F.Cu" "F.Mask" "F.Paste")
			(net "M_C_CPU0_SA_DQ<5>")
		)
		(pad "U76" smd circle
			(at 25.216612 -19.445732 270)
			(size 0.4318 0.4318)
			(layers "F.Cu" "F.Mask" "F.Paste")
			(net "M_C_CPU0_SA_DQS_DP<0>")
		)
		(pad "U78" smd circle
			(at 26.844498 -19.445732 270)
			(size 0.4318 0.4318)
			(layers "F.Cu" "F.Mask" "F.Paste")
			(net "M_C_CPU0_SA_DQ<0>")
		)
		(pad "U80" smd circle
			(at 28.472384 -19.445732 270)
			(size 0.4318 0.4318)
			(layers "F.Cu" "F.Mask" "F.Paste")
			(net "UPI_CPU0_CPU1_P2P2_DN<16>")
		)
		(pad "U82" smd circle
			(at 30.100016 -19.445732 270)
			(size 0.4318 0.4318)
			(layers "F.Cu" "F.Mask" "F.Paste")
			(net "GND")
		)
		(pad "U84" smd circle
			(at 31.727902 -19.445732 270)
			(size 0.4318 0.4318)
			(layers "F.Cu" "F.Mask" "F.Paste")
			(net "GND")
		)
		(pad "U86" smd circle
			(at 33.355534 -19.445732 270)
			(size 0.4318 0.4318)
			(layers "F.Cu" "F.Mask" "F.Paste")
			(net "P5E_CPU0_PE4_TX_DN<3>")
		)
		(pad "U88" smd circle
			(at 34.98342 -19.445732 270)
			(size 0.4318 0.4318)
			(layers "F.Cu" "F.Mask" "F.Paste")
			(net "GND")
		)
	)
)
